(kicad_pcb
	(version 20260206)
	(generator "pcbnew")
	(generator_version "10.0")
	(general
		(thickness 1.6)
		(legacy_teardrops no)
	)
	(paper "A4")
	(title_block
		(title "Bryce Canyon_IOM_IOC_16318-2_OCP.brd")
		(comment 1 "Bryce Canyon / footprints 265-271 of 1605")
	)
	(layers
		(0 "F.Cu" signal "TOP")
		(4 "In1.Cu" signal "L2GND")
		(6 "In2.Cu" signal "L3")
		(8 "In3.Cu" signal "L4VCC")
		(10 "In4.Cu" signal "L5VCC")
		(12 "In5.Cu" signal "L6")
		(14 "In6.Cu" signal "L7GND")
		(2 "B.Cu" signal "BOTTOM")
		(9 "F.Adhes" user "F.Adhesive")
		(11 "B.Adhes" user "B.Adhesive")
		(13 "F.Paste" user "Package Geometry/Pastemask Top")
		(15 "B.Paste" user "Package Geometry/Pastemask Bottom")
		(5 "F.SilkS" user "Ref Des/Silkscreen Top")
		(7 "B.SilkS" user "Ref Des/Silkscreen Bottom")
		(1 "F.Mask" user "Board Geometry/Soldermask Top")
		(3 "B.Mask" user "Board Geometry/Soldermask Bottom")
		(17 "Dwgs.User" user "User.Drawings")
		(19 "Cmts.User" user "User.Comments")
		(21 "Eco1.User" user "User.Eco1")
		(23 "Eco2.User" user "User.Eco2")
		(25 "Edge.Cuts" user "Board Geometry/Outline")
		(27 "Margin" user)
		(31 "F.CrtYd" user "Package Geometry/Place Bound Top")
		(29 "B.CrtYd" user "Package Geometry/Place Bound Bottom")
		(35 "F.Fab" user "Ref Des/Assembly Top")
		(33 "B.Fab" user "Ref Des/Assembly Bottom")
	)
	(footprint ""
		(layer "F.Cu")
		(at 47.060104 -161.180272 180)
		(property "Reference" "R179"
			(at 0 0 180)
			(layer "F.SilkS")
			(hide yes)
			(effects
				(font
					(size 1.27 1.27)
				)
			)
		)
		(property "Value" "2K2R2F-GP"
			(at 0.064008 -3.993896 180)
			(unlocked yes)
			(layer "F.Fab")
			(hide yes)
			(effects
				(font
					(size 1.016 1.016)
					(thickness 0.1524)
				)
			)
		)
		(property "Device Type" "R402H16"
			(at 0.064008 -5.517896 180)
			(unlocked yes)
			(layer "F.Fab")
			(hide yes)
			(effects
				(font
					(size 1.016 1.016)
					(thickness 0.1524)
				)
			)
		)
		(duplicate_pad_numbers_are_jumpers no)
		(fp_line
			(start 0.508 -0.9398)
			(end -0.508 -0.9398)
			(stroke
				(width 0.1524)
				(type default)
			)
			(layer "F.SilkS")
		)
		(fp_line
			(start -0.508 -0.9398)
			(end -0.508 0.9398)
			(stroke
				(width 0.1524)
				(type default)
			)
			(layer "F.SilkS")
		)
		(fp_rect
			(start -0.508 0.9398)
			(end 0.508 -0.9398)
			(stroke
				(width 0)
				(type default)
			)
			(fill no)
			(layer "F.CrtYd")
		)
		(fp_rect
			(start -0.508 0.9398)
			(end 0.508 -0.9398)
			(stroke
				(width 0)
				(type default)
			)
			(fill no)
			(layer "F.Fab")
		)
		(pad "1" smd custom
			(at 0 -0.4445 180)
			(size 0.1397 0.1397)
			(layers "F.Cu" "F.Mask" "F.Paste")
			(net "I2C_DPB_SCL_OUT")
			(options
				(clearance outline)
				(anchor circle)
			)
			(primitives
				(gr_poly
					(pts
						(arc
							(start -0.1778 -0.2794)
							(mid -0.249642 -0.249642)
							(end -0.2794 -0.1778)
						)
						(arc
							(start -0.2794 0.1778)
							(mid -0.249642 0.249642)
							(end -0.1778 0.2794)
						)
						(arc
							(start 0.1778 0.2794)
							(mid 0.249642 0.249642)
							(end 0.2794 0.1778)
						)
						(arc
							(start 0.2794 -0.1778)
							(mid 0.249642 -0.249642)
							(end 0.1778 -0.2794)
						)
					)
					(width 0)
					(fill yes)
				)
			)
		)
		(pad "2" smd custom
			(at 0 0.4445 180)
			(size 0.1397 0.1397)
			(layers "F.Cu" "F.Mask" "F.Paste")
			(net "P3V3_STBY")
			(options
				(clearance outline)
				(anchor circle)
			)
			(primitives
				(gr_poly
					(pts
						(arc
							(start -0.1778 -0.2794)
							(mid -0.249642 -0.249642)
							(end -0.2794 -0.1778)
						)
						(arc
							(start -0.2794 0.1778)
							(mid -0.249642 0.249642)
							(end -0.1778 0.2794)
						)
						(arc
							(start 0.1778 0.2794)
							(mid 0.249642 0.249642)
							(end 0.2794 0.1778)
						)
						(arc
							(start 0.2794 -0.1778)
							(mid 0.249642 -0.249642)
							(end 0.1778 -0.2794)
						)
					)
					(width 0)
					(fill yes)
				)
			)
		)
	)
	(footprint ""
		(layer "F.Cu")
		(at 73.05548 -185.90768)
		(property "Reference" "R508"
			(at 0 0 0)
			(layer "F.SilkS")
			(hide yes)
			(effects
				(font
					(size 1.27 1.27)
				)
			)
		)
		(property "Value" "0R2J-2-GP"
			(at 0.064008 -3.993896 0)
			(unlocked yes)
			(layer "F.Fab")
			(hide yes)
			(effects
				(font
					(size 1.016 1.016)
					(thickness 0.1524)
				)
			)
		)
		(property "Device Type" "R402H16"
			(at 0.064008 -5.517896 0)
			(unlocked yes)
			(layer "F.Fab")
			(hide yes)
			(effects
				(font
					(size 1.016 1.016)
					(thickness 0.1524)
				)
			)
		)
		(duplicate_pad_numbers_are_jumpers no)
		(fp_line
			(start -0.508 -0.9398)
			(end -0.508 0.9398)
			(stroke
				(width 0.1524)
				(type default)
			)
			(layer "F.SilkS")
		)
		(fp_line
			(start 0.508 -0.9398)
			(end -0.508 -0.9398)
			(stroke
				(width 0.1524)
				(type default)
			)
			(layer "F.SilkS")
		)
		(fp_rect
			(start -0.508 0.9398)
			(end 0.508 -0.9398)
			(stroke
				(width 0)
				(type default)
			)
			(fill no)
			(layer "F.CrtYd")
		)
		(fp_rect
			(start -0.508 0.9398)
			(end 0.508 -0.9398)
			(stroke
				(width 0)
				(type default)
			)
			(fill no)
			(layer "F.Fab")
		)
		(pad "1" smd custom
			(at 0 -0.4445)
			(size 0.1397 0.1397)
			(layers "F.Cu" "F.Mask" "F.Paste")
			(net "P5V_STBY")
			(options
				(clearance outline)
				(anchor circle)
			)
			(primitives
				(gr_poly
					(pts
						(arc
							(start -0.1778 -0.2794)
							(mid -0.249642 -0.249642)
							(end -0.2794 -0.1778)
						)
						(arc
							(start -0.2794 0.1778)
							(mid -0.249642 0.249642)
							(end -0.1778 0.2794)
						)
						(arc
							(start 0.1778 0.2794)
							(mid 0.249642 0.249642)
							(end 0.2794 0.1778)
						)
						(arc
							(start 0.2794 -0.1778)
							(mid 0.249642 -0.249642)
							(end 0.1778 -0.2794)
						)
					)
					(width 0)
					(fill yes)
				)
			)
		)
		(pad "2" smd custom
			(at 0 0.4445)
			(size 0.1397 0.1397)
			(layers "F.Cu" "F.Mask" "F.Paste")
			(net "TPS74801_P2V5_STBY_BIAS")
			(options
				(clearance outline)
				(anchor circle)
			)
			(primitives
				(gr_poly
					(pts
						(arc
							(start -0.1778 -0.2794)
							(mid -0.249642 -0.249642)
							(end -0.2794 -0.1778)
						)
						(arc
							(start -0.2794 0.1778)
							(mid -0.249642 0.249642)
							(end -0.1778 0.2794)
						)
						(arc
							(start 0.1778 0.2794)
							(mid 0.249642 0.249642)
							(end 0.2794 0.1778)
						)
						(arc
							(start 0.2794 -0.1778)
							(mid 0.249642 -0.249642)
							(end 0.1778 -0.2794)
						)
					)
					(width 0)
					(fill yes)
				)
			)
		)
	)
	(footprint ""
		(layer "F.Cu")
		(at 208.661 -81.915 90)
		(property "Reference" "R569"
			(at 0 0 90)
			(layer "F.SilkS")
			(hide yes)
			(effects
				(font
					(size 1.27 1.27)
				)
			)
		)
		(property "Value" "51R2F-2-GP"
			(at 0.064008 -3.993896 90)
			(unlocked yes)
			(layer "F.Fab")
			(hide yes)
			(effects
				(font
					(size 1.016 1.016)
					(thickness 0.1524)
				)
			)
		)
		(property "Device Type" "R402H16"
			(at 0.064008 -5.517896 90)
			(unlocked yes)
			(layer "F.Fab")
			(hide yes)
			(effects
				(font
					(size 1.016 1.016)
					(thickness 0.1524)
				)
			)
		)
		(duplicate_pad_numbers_are_jumpers no)
		(fp_line
			(start 0.508 -0.9398)
			(end -0.508 -0.9398)
			(stroke
				(width 0.1524)
				(type default)
			)
			(layer "F.SilkS")
		)
		(fp_line
			(start -0.508 -0.9398)
			(end -0.508 0.9398)
			(stroke
				(width 0.1524)
				(type default)
			)
			(layer "F.SilkS")
		)
		(fp_rect
			(start -0.508 0.9398)
			(end 0.508 -0.9398)
			(stroke
				(width 0)
				(type default)
			)
			(fill no)
			(layer "F.CrtYd")
		)
		(fp_rect
			(start -0.508 0.9398)
			(end 0.508 -0.9398)
			(stroke
				(width 0)
				(type default)
			)
			(fill no)
			(layer "F.Fab")
		)
		(pad "1" smd custom
			(at 0 -0.4445 90)
			(size 0.1397 0.1397)
			(layers "F.Cu" "F.Mask" "F.Paste")
			(net "PCIE_COMP_TO_IOM_CLK_2_DP")
			(options
				(clearance outline)
				(anchor circle)
			)
			(primitives
				(gr_poly
					(pts
						(arc
							(start -0.1778 -0.2794)
							(mid -0.249642 -0.249642)
							(end -0.2794 -0.1778)
						)
						(arc
							(start -0.2794 0.1778)
							(mid -0.249642 0.249642)
							(end -0.1778 0.2794)
						)
						(arc
							(start 0.1778 0.2794)
							(mid 0.249642 0.249642)
							(end 0.2794 0.1778)
						)
						(arc
							(start 0.2794 -0.1778)
							(mid 0.249642 -0.249642)
							(end 0.1778 -0.2794)
						)
					)
					(width 0)
					(fill yes)
				)
			)
		)
		(pad "2" smd custom
			(at 0 0.4445 90)
			(size 0.1397 0.1397)
			(layers "F.Cu" "F.Mask" "F.Paste")
			(net "GND")
			(options
				(clearance outline)
				(anchor circle)
			)
			(primitives
				(gr_poly
					(pts
						(arc
							(start -0.1778 -0.2794)
							(mid -0.249642 -0.249642)
							(end -0.2794 -0.1778)
						)
						(arc
							(start -0.2794 0.1778)
							(mid -0.249642 0.249642)
							(end -0.1778 0.2794)
						)
						(arc
							(start 0.1778 0.2794)
							(mid 0.249642 0.249642)
							(end 0.2794 0.1778)
						)
						(arc
							(start 0.2794 -0.1778)
							(mid 0.249642 -0.249642)
							(end 0.1778 -0.2794)
						)
					)
					(width 0)
					(fill yes)
				)
			)
		)
	)
	(footprint ""
		(layer "F.Cu")
		(at 30.912562 -154.893772 90)
		(property "Reference" "R331"
			(at 0 0 90)
			(layer "F.SilkS")
			(hide yes)
			(effects
				(font
					(size 1.27 1.27)
				)
			)
		)
		(property "Value" "4K7R2F-GP"
			(at 0.064008 -3.993896 90)
			(unlocked yes)
			(layer "F.Fab")
			(hide yes)
			(effects
				(font
					(size 1.016 1.016)
					(thickness 0.1524)
				)
			)
		)
		(property "Device Type" "R402H16"
			(at 0.064008 -5.517896 90)
			(unlocked yes)
			(layer "F.Fab")
			(hide yes)
			(effects
				(font
					(size 1.016 1.016)
					(thickness 0.1524)
				)
			)
		)
		(duplicate_pad_numbers_are_jumpers no)
		(fp_line
			(start 0.508 -0.9398)
			(end -0.508 -0.9398)
			(stroke
				(width 0.1524)
				(type default)
			)
			(layer "F.SilkS")
		)
		(fp_line
			(start -0.508 -0.9398)
			(end -0.508 0.9398)
			(stroke
				(width 0.1524)
				(type default)
			)
			(layer "F.SilkS")
		)
		(fp_rect
			(start -0.508 0.9398)
			(end 0.508 -0.9398)
			(stroke
				(width 0)
				(type default)
			)
			(fill no)
			(layer "F.CrtYd")
		)
		(fp_rect
			(start -0.508 0.9398)
			(end 0.508 -0.9398)
			(stroke
				(width 0)
				(type default)
			)
			(fill no)
			(layer "F.Fab")
		)
		(pad "1" smd custom
			(at 0 -0.4445 90)
			(size 0.1397 0.1397)
			(layers "F.Cu" "F.Mask" "F.Paste")
			(net "P3V3_STBY")
			(options
				(clearance outline)
				(anchor circle)
			)
			(primitives
				(gr_poly
					(pts
						(arc
							(start -0.1778 -0.2794)
							(mid -0.249642 -0.249642)
							(end -0.2794 -0.1778)
						)
						(arc
							(start -0.2794 0.1778)
							(mid -0.249642 0.249642)
							(end -0.1778 0.2794)
						)
						(arc
							(start 0.1778 0.2794)
							(mid 0.249642 0.249642)
							(end 0.2794 0.1778)
						)
						(arc
							(start 0.2794 -0.1778)
							(mid 0.249642 -0.249642)
							(end 0.1778 -0.2794)
						)
					)
					(width 0)
					(fill yes)
				)
			)
		)
		(pad "2" smd custom
			(at 0 0.4445 90)
			(size 0.1397 0.1397)
			(layers "F.Cu" "F.Mask" "F.Paste")
			(net "COMP_POWER_FAIL_N")
			(options
				(clearance outline)
				(anchor circle)
			)
			(primitives
				(gr_poly
					(pts
						(arc
							(start -0.1778 -0.2794)
							(mid -0.249642 -0.249642)
							(end -0.2794 -0.1778)
						)
						(arc
							(start -0.2794 0.1778)
							(mid -0.249642 0.249642)
							(end -0.1778 0.2794)
						)
						(arc
							(start 0.1778 0.2794)
							(mid 0.249642 0.249642)
							(end 0.2794 0.1778)
						)
						(arc
							(start 0.2794 -0.1778)
							(mid 0.249642 -0.249642)
							(end 0.1778 -0.2794)
						)
					)
					(width 0)
					(fill yes)
				)
			)
		)
	)
	(footprint ""
		(layer "F.Cu")
		(at 32.6898 -135.7884 90)
		(property "Reference" "R283"
			(at 0 0 90)
			(layer "F.SilkS")
			(hide yes)
			(effects
				(font
					(size 1.27 1.27)
				)
			)
		)
		(property "Value" "33R2F-3-GP"
			(at 0.064008 -3.993896 90)
			(unlocked yes)
			(layer "F.Fab")
			(hide yes)
			(effects
				(font
					(size 1.016 1.016)
					(thickness 0.1524)
				)
			)
		)
		(property "Device Type" "R402H16"
			(at 0.064008 -5.517896 90)
			(unlocked yes)
			(layer "F.Fab")
			(hide yes)
			(effects
				(font
					(size 1.016 1.016)
					(thickness 0.1524)
				)
			)
		)
		(duplicate_pad_numbers_are_jumpers no)
		(fp_line
			(start 0.508 -0.9398)
			(end -0.508 -0.9398)
			(stroke
				(width 0.1524)
				(type default)
			)
			(layer "F.SilkS")
		)
		(fp_line
			(start -0.508 -0.9398)
			(end -0.508 0.9398)
			(stroke
				(width 0.1524)
				(type default)
			)
			(layer "F.SilkS")
		)
		(fp_rect
			(start -0.508 0.9398)
			(end 0.508 -0.9398)
			(stroke
				(width 0)
				(type default)
			)
			(fill no)
			(layer "F.CrtYd")
		)
		(fp_rect
			(start -0.508 0.9398)
			(end 0.508 -0.9398)
			(stroke
				(width 0)
				(type default)
			)
			(fill no)
			(layer "F.Fab")
		)
		(pad "1" smd custom
			(at 0 -0.4445 90)
			(size 0.1397 0.1397)
			(layers "F.Cu" "F.Mask" "F.Paste")
			(net "BMC_SPI_CLK_R")
			(options
				(clearance outline)
				(anchor circle)
			)
			(primitives
				(gr_poly
					(pts
						(arc
							(start -0.1778 -0.2794)
							(mid -0.249642 -0.249642)
							(end -0.2794 -0.1778)
						)
						(arc
							(start -0.2794 0.1778)
							(mid -0.249642 0.249642)
							(end -0.1778 0.2794)
						)
						(arc
							(start 0.1778 0.2794)
							(mid 0.249642 0.249642)
							(end 0.2794 0.1778)
						)
						(arc
							(start 0.2794 -0.1778)
							(mid 0.249642 -0.249642)
							(end 0.1778 -0.2794)
						)
					)
					(width 0)
					(fill yes)
				)
			)
		)
		(pad "2" smd custom
			(at 0 0.4445 90)
			(size 0.1397 0.1397)
			(layers "F.Cu" "F.Mask" "F.Paste")
			(net "BMC_SPI_CLK")
			(options
				(clearance outline)
				(anchor circle)
			)
			(primitives
				(gr_poly
					(pts
						(arc
							(start -0.1778 -0.2794)
							(mid -0.249642 -0.249642)
							(end -0.2794 -0.1778)
						)
						(arc
							(start -0.2794 0.1778)
							(mid -0.249642 0.249642)
							(end -0.1778 0.2794)
						)
						(arc
							(start 0.1778 0.2794)
							(mid 0.249642 0.249642)
							(end 0.2794 0.1778)
						)
						(arc
							(start 0.2794 -0.1778)
							(mid 0.249642 -0.249642)
							(end 0.1778 -0.2794)
						)
					)
					(width 0)
					(fill yes)
				)
			)
		)
	)
	(footprint ""
		(layer "F.Cu")
		(at 10.7442 -139.573 90)
		(property "Reference" "R218"
			(at 0 0 90)
			(layer "F.SilkS")
			(hide yes)
			(effects
				(font
					(size 1.27 1.27)
				)
			)
		)
		(property "Value" "120R2F-GP"
			(at 0.064008 -3.993896 90)
			(unlocked yes)
			(layer "F.Fab")
			(hide yes)
			(effects
				(font
					(size 1.016 1.016)
					(thickness 0.1524)
				)
			)
		)
		(property "Device Type" "R402H16"
			(at 0.064008 -5.517896 90)
			(unlocked yes)
			(layer "F.Fab")
			(hide yes)
			(effects
				(font
					(size 1.016 1.016)
					(thickness 0.1524)
				)
			)
		)
		(duplicate_pad_numbers_are_jumpers no)
		(fp_line
			(start 0.508 -0.9398)
			(end -0.508 -0.9398)
			(stroke
				(width 0.1524)
				(type default)
			)
			(layer "F.SilkS")
		)
		(fp_line
			(start -0.508 -0.9398)
			(end -0.508 0.9398)
			(stroke
				(width 0.1524)
				(type default)
			)
			(layer "F.SilkS")
		)
		(fp_rect
			(start -0.508 0.9398)
			(end 0.508 -0.9398)
			(stroke
				(width 0)
				(type default)
			)
			(fill no)
			(layer "F.CrtYd")
		)
		(fp_rect
			(start -0.508 0.9398)
			(end 0.508 -0.9398)
			(stroke
				(width 0)
				(type default)
			)
			(fill no)
			(layer "F.Fab")
		)
		(pad "1" smd custom
			(at 0 -0.4445 90)
			(size 0.1397 0.1397)
			(layers "F.Cu" "F.Mask" "F.Paste")
			(net "MEMBG_0")
			(options
				(clearance outline)
				(anchor circle)
			)
			(primitives
				(gr_poly
					(pts
						(arc
							(start -0.1778 -0.2794)
							(mid -0.249642 -0.249642)
							(end -0.2794 -0.1778)
						)
						(arc
							(start -0.2794 0.1778)
							(mid -0.249642 0.249642)
							(end -0.1778 0.2794)
						)
						(arc
							(start 0.1778 0.2794)
							(mid 0.249642 0.249642)
							(end 0.2794 0.1778)
						)
						(arc
							(start 0.2794 -0.1778)
							(mid 0.249642 -0.249642)
							(end 0.1778 -0.2794)
						)
					)
					(width 0)
					(fill yes)
				)
			)
		)
		(pad "2" smd custom
			(at 0 0.4445 90)
			(size 0.1397 0.1397)
			(layers "F.Cu" "F.Mask" "F.Paste")
			(net "P1V2_STBY")
			(options
				(clearance outline)
				(anchor circle)
			)
			(primitives
				(gr_poly
					(pts
						(arc
							(start -0.1778 -0.2794)
							(mid -0.249642 -0.249642)
							(end -0.2794 -0.1778)
						)
						(arc
							(start -0.2794 0.1778)
							(mid -0.249642 0.249642)
							(end -0.1778 0.2794)
						)
						(arc
							(start 0.1778 0.2794)
							(mid 0.249642 0.249642)
							(end 0.2794 0.1778)
						)
						(arc
							(start 0.2794 -0.1778)
							(mid 0.249642 -0.249642)
							(end 0.1778 -0.2794)
						)
					)
					(width 0)
					(fill yes)
				)
			)
		)
	)
	(footprint ""
		(layer "F.Cu")
		(at 68.4784 -120.523 90)
		(property "Reference" "R764"
			(at 0 0 90)
			(layer "F.SilkS")
			(hide yes)
			(effects
				(font
					(size 1.27 1.27)
				)
			)
		)
		(property "Value" "0R2J-2-GP"
			(at 0.064008 -3.993896 90)
			(unlocked yes)
			(layer "F.Fab")
			(hide yes)
			(effects
				(font
					(size 1.016 1.016)
					(thickness 0.1524)
				)
			)
		)
		(property "Device Type" "R402H16"
			(at 0.064008 -5.517896 90)
			(unlocked yes)
			(layer "F.Fab")
			(hide yes)
			(effects
				(font
					(size 1.016 1.016)
					(thickness 0.1524)
				)
			)
		)
		(duplicate_pad_numbers_are_jumpers no)
		(fp_line
			(start 0.508 -0.9398)
			(end -0.508 -0.9398)
			(stroke
				(width 0.1524)
				(type default)
			)
			(layer "F.SilkS")
		)
		(fp_line
			(start -0.508 -0.9398)
			(end -0.508 0.9398)
			(stroke
				(width 0.1524)
				(type default)
			)
			(layer "F.SilkS")
		)
		(fp_rect
			(start -0.508 0.9398)
			(end 0.508 -0.9398)
			(stroke
				(width 0)
				(type default)
			)
			(fill no)
			(layer "F.CrtYd")
		)
		(fp_rect
			(start -0.508 0.9398)
			(end 0.508 -0.9398)
			(stroke
				(width 0)
				(type default)
			)
			(fill no)
			(layer "F.Fab")
		)
		(pad "1" smd custom
			(at 0 -0.4445 90)
			(size 0.1397 0.1397)
			(layers "F.Cu" "F.Mask" "F.Paste")
			(net "FLA1_SPI_RST")
			(options
				(clearance outline)
				(anchor circle)
			)
			(primitives
				(gr_poly
					(pts
						(arc
							(start -0.1778 -0.2794)
							(mid -0.249642 -0.249642)
							(end -0.2794 -0.1778)
						)
						(arc
							(start -0.2794 0.1778)
							(mid -0.249642 0.249642)
							(end -0.1778 0.2794)
						)
						(arc
							(start 0.1778 0.2794)
							(mid 0.249642 0.249642)
							(end 0.2794 0.1778)
						)
						(arc
							(start 0.2794 -0.1778)
							(mid 0.249642 -0.249642)
							(end 0.1778 -0.2794)
						)
					)
					(width 0)
					(fill yes)
				)
			)
		)
		(pad "2" smd custom
			(at 0 0.4445 90)
			(size 0.1397 0.1397)
			(layers "F.Cu" "F.Mask" "F.Paste")
			(net "RST_BMC_EXTRST_N")
			(options
				(clearance outline)
				(anchor circle)
			)
			(primitives
				(gr_poly
					(pts
						(arc
							(start -0.1778 -0.2794)
							(mid -0.249642 -0.249642)
							(end -0.2794 -0.1778)
						)
						(arc
							(start -0.2794 0.1778)
							(mid -0.249642 0.249642)
							(end -0.1778 0.2794)
						)
						(arc
							(start 0.1778 0.2794)
							(mid 0.249642 0.249642)
							(end 0.2794 0.1778)
						)
						(arc
							(start 0.2794 -0.1778)
							(mid 0.249642 -0.249642)
							(end 0.1778 -0.2794)
						)
					)
					(width 0)
					(fill yes)
				)
			)
		)
	)
)
